(kicad_pcb
	(version 20260206)
	(generator "pcbnew")
	(generator_version "10.0")
	(general
		(thickness 1.6)
		(legacy_teardrops no)
	)
	(paper "A4")
	(title_block
		(title "Wiwynn_Tioga_Pass_MB.brd")
		(comment 1 "Tioga Pass / footprint 153 of 4770 (U25W4), pads 1-106 of 456")
	)
	(layers
		(0 "F.Cu" signal "TOP")
		(4 "In1.Cu" signal "L2GND")
		(6 "In2.Cu" signal "L3")
		(8 "In3.Cu" signal "L4GND")
		(10 "In4.Cu" signal "L5")
		(12 "In5.Cu" signal "L6GND")
		(14 "In6.Cu" signal "L7VCC")
		(16 "In7.Cu" signal "L8VCC")
		(18 "In8.Cu" signal "L9GND")
		(20 "In9.Cu" signal "L10")
		(22 "In10.Cu" signal "L11GND")
		(24 "In11.Cu" signal "L12")
		(26 "In12.Cu" signal "L13GND")
		(2 "B.Cu" signal "BOTTOM")
		(9 "F.Adhes" user "F.Adhesive")
		(11 "B.Adhes" user "B.Adhesive")
		(13 "F.Paste" user "Package Geometry/Pastemask Top")
		(15 "B.Paste" user "Package Geometry/Pastemask Bottom")
		(5 "F.SilkS" user "Ref Des/Silkscreen Top")
		(7 "B.SilkS" user "Ref Des/Silkscreen Bottom")
		(1 "F.Mask" user "Board Geometry/Soldermask Top")
		(3 "B.Mask" user "Board Geometry/Soldermask Bottom")
		(17 "Dwgs.User" user "User.Drawings")
		(19 "Cmts.User" user "User.Comments")
		(21 "Eco1.User" user "User.Eco1")
		(23 "Eco2.User" user "User.Eco2")
		(25 "Edge.Cuts" user "Board Geometry/Outline")
		(27 "Margin" user)
		(31 "F.CrtYd" user "Package Geometry/Place Bound Top")
		(29 "B.CrtYd" user "Package Geometry/Place Bound Bottom")
		(35 "F.Fab" user "Ref Des/Assembly Top")
		(33 "B.Fab" user "Ref Des/Assembly Bottom")
	)
	(footprint ""
		(layer "F.Cu")
		(at 415.490152 -34.934652 90)
		(property "Reference" "U25W4"
			(at 0 0 90)
			(layer "F.SilkS")
			(hide yes)
			(effects
				(font
					(size 1.27 1.27)
				)
			)
		)
		(property "Value" "*"
			(at -17.0307 -8.698992 90)
			(unlocked yes)
			(layer "F.Fab")
			(hide yes)
			(effects
				(font
					(size 1.27 1.016)
					(thickness 0.1524)
				)
			)
		)
		(property "Device Type" "AST2520A1-GP-GP_ASIC2-GB1-AST2A"
			(at -17.0307 -10.222992 90)
			(unlocked yes)
			(layer "F.Fab")
			(hide yes)
			(effects
				(font
					(size 1.27 1.016)
					(thickness 0.1524)
				)
			)
		)
		(duplicate_pad_numbers_are_jumpers no)
		(pad "A1" smd circle
			(at -8.400034 -8.400034 90)
			(size 0.4064 0.4064)
			(layers "F.Cu" "F.Mask" "F.Paste")
			(net "GND")
		)
		(pad "A2" smd circle
			(at -7.599934 -8.400034 90)
			(size 0.4064 0.4064)
			(layers "F.Cu" "F.Mask" "F.Paste")
			(net "RMII_BMC_PCH_SPRNGVLLE_TXD0_R")
		)
		(pad "A3" smd circle
			(at -6.800088 -8.400034 90)
			(size 0.4064 0.4064)
			(layers "F.Cu" "F.Mask" "F.Paste")
			(net "RMII_BMC_OCP_RXD0")
		)
		(pad "A4" smd circle
			(at -5.999988 -8.400034 90)
			(size 0.3556 0.3556)
			(layers "F.Cu" "F.Mask" "F.Paste")
			(net "FM_BMC_FAULT_LED_N")
		)
		(pad "A5" smd circle
			(at -5.199888 -8.400034 90)
			(size 0.3556 0.3556)
			(layers "F.Cu" "F.Mask" "F.Paste")
			(net "RMII_BMC_OCP_TXD1_R")
		)
		(pad "A6" smd circle
			(at -4.400042 -8.400034 90)
			(size 0.3556 0.3556)
			(layers "F.Cu" "F.Mask" "F.Paste")
			(net "USB2_PCH_BMC_P5_DN")
		)
		(pad "A7" smd circle
			(at -3.599942 -8.400034 90)
			(size 0.3556 0.3556)
			(layers "F.Cu" "F.Mask" "F.Paste")
			(net "USB_PCH_BMC_P4_DP")
		)
		(pad "A8" smd circle
			(at -2.800096 -8.400034 90)
			(size 0.3556 0.3556)
			(layers "F.Cu" "F.Mask" "F.Paste")
			(net "USB_PCH_BMC_P4_DN")
		)
		(pad "A9" smd circle
			(at -1.999996 -8.400034 90)
			(size 0.3556 0.3556)
			(layers "F.Cu" "F.Mask" "F.Paste")
			(net "SMB_HOST_STBY_LVC3_SCL_R")
		)
		(pad "A10" smd circle
			(at -1.199896 -8.400034 90)
			(size 0.3556 0.3556)
			(layers "F.Cu" "F.Mask" "F.Paste")
			(net "SMB_OCP_LAN_STBY_LVC3_SDA_R")
		)
		(pad "A11" smd circle
			(at -0.40005 -8.400034 90)
			(size 0.3556 0.3556)
			(layers "F.Cu" "F.Mask" "F.Paste")
			(net "SMB_OCP_LAN_STBY_LVC3_SCL_R")
		)
		(pad "A12" smd circle
			(at 0.40005 -8.400034 90)
			(size 0.3556 0.3556)
			(layers "F.Cu" "F.Mask" "F.Paste")
			(net "SMB_DEBUG_STBY_LVC3_SDA_R")
		)
		(pad "A13" smd circle
			(at 1.199896 -8.400034 90)
			(size 0.3556 0.3556)
			(layers "F.Cu" "F.Mask" "F.Paste")
			(net "SMB_OCP_FRU_STBY_LVC3_SDA_R")
		)
		(pad "A14" smd circle
			(at 1.999996 -8.400034 90)
			(size 0.3556 0.3556)
			(layers "F.Cu" "F.Mask" "F.Paste")
			(net "SPI_BMC_DO")
		)
		(pad "A15" smd circle
			(at 2.800096 -8.400034 90)
			(size 0.3556 0.3556)
			(layers "F.Cu" "F.Mask" "F.Paste")
			(net "SPI_BMC_DI")
		)
		(pad "A16" smd circle
			(at 3.599942 -8.400034 90)
			(size 0.3556 0.3556)
			(layers "F.Cu" "F.Mask" "F.Paste")
			(net "LED_POSTCODE_6")
		)
		(pad "A17" smd circle
			(at 4.400042 -8.400034 90)
			(size 0.3556 0.3556)
			(layers "F.Cu" "F.Mask" "F.Paste")
			(net "LED_POSTCODE_4")
		)
		(pad "A18" smd circle
			(at 5.199888 -8.400034 90)
			(size 0.3556 0.3556)
			(layers "F.Cu" "F.Mask" "F.Paste")
			(net "LED_POSTCODE_0")
		)
		(pad "A19" smd circle
			(at 5.999988 -8.400034 90)
			(size 0.3556 0.3556)
			(layers "F.Cu" "F.Mask" "F.Paste")
			(net "FM_CPU_ERR2_LVT3_N")
		)
		(pad "A20" smd circle
			(at 6.800088 -8.400034 90)
			(size 0.4064 0.4064)
			(layers "F.Cu" "F.Mask" "F.Paste")
			(net "FM_CPU0_PROCHOT_LVT3_BMC_N")
		)
		(pad "A21" smd circle
			(at 7.599934 -8.400034 90)
			(size 0.4064 0.4064)
			(layers "F.Cu" "F.Mask" "F.Paste")
			(net "IRQ_PVDDQ_KLM_VRHOT_LVT3_N")
		)
		(pad "A22" smd circle
			(at 8.400034 -8.400034 90)
			(size 0.4064 0.4064)
			(layers "F.Cu" "F.Mask" "F.Paste")
			(net "GND")
		)
		(pad "AA1" smd circle
			(at -8.400034 7.599934 90)
			(size 0.4064 0.4064)
			(layers "F.Cu" "F.Mask" "F.Paste")
			(net "IRQ_BOARD_BMC_ALERT_N")
		)
		(pad "AA2" smd circle
			(at -7.599934 7.599934 90)
			(size 0.4064 0.4064)
			(layers "F.Cu" "F.Mask" "F.Paste")
			(net "FM_CPU0_THERMTRIP_LATCH_LVT3_N")
		)
		(pad "AA3" smd circle
			(at -6.800088 7.599934 90)
			(size 0.4064 0.4064)
			(layers "F.Cu" "F.Mask" "F.Paste")
			(net "FM_BIOS_SPI_BMC_CTRL")
		)
		(pad "AA4" smd circle
			(at -5.999988 7.599934 90)
			(size 0.3556 0.3556)
			(layers "F.Cu" "F.Mask" "F.Paste")
			(net "FM_XRC_PRESENT_N")
		)
		(pad "AA5" smd circle
			(at -5.199888 7.599934 90)
			(size 0.3556 0.3556)
			(layers "F.Cu" "F.Mask" "F.Paste")
			(net "FM_BOARD_SKU_ID2")
		)
		(pad "AA6" smd circle
			(at -4.400042 7.599934 90)
			(size 0.3556 0.3556)
			(layers "F.Cu" "F.Mask" "F.Paste")
			(net "BMC_M_DQ12")
		)
		(pad "AA7" smd circle
			(at -3.599942 7.599934 90)
			(size 0.3556 0.3556)
			(layers "F.Cu" "F.Mask" "F.Paste")
			(net "GND")
		)
		(pad "AA8" smd circle
			(at -2.800096 7.599934 90)
			(size 0.3556 0.3556)
			(layers "F.Cu" "F.Mask" "F.Paste")
			(net "BMC_M_DQ8")
		)
		(pad "AA9" smd circle
			(at -1.999996 7.599934 90)
			(size 0.3556 0.3556)
			(layers "F.Cu" "F.Mask" "F.Paste")
			(net "GND")
		)
		(pad "AA10" smd circle
			(at -1.199896 7.599934 90)
			(size 0.3556 0.3556)
			(layers "F.Cu" "F.Mask" "F.Paste")
			(net "BMC_M_DQ3")
		)
		(pad "AA11" smd circle
			(at -0.40005 7.599934 90)
			(size 0.3556 0.3556)
			(layers "F.Cu" "F.Mask" "F.Paste")
			(net "GND")
		)
		(pad "AA12" smd circle
			(at 0.40005 7.599934 90)
			(size 0.3556 0.3556)
			(layers "F.Cu" "F.Mask" "F.Paste")
			(net "BMC_M_CS_N")
		)
		(pad "AA13" smd circle
			(at 1.199896 7.599934 90)
			(size 0.3556 0.3556)
			(layers "F.Cu" "F.Mask" "F.Paste")
			(net "GND")
		)
		(pad "AA14" smd circle
			(at 1.999996 7.599934 90)
			(size 0.3556 0.3556)
			(layers "F.Cu" "F.Mask" "F.Paste")
			(net "BMC_M_A11")
		)
		(pad "AA15" smd circle
			(at 2.800096 7.599934 90)
			(size 0.3556 0.3556)
			(layers "F.Cu" "F.Mask" "F.Paste")
			(net "GND")
		)
		(pad "AA16" smd circle
			(at 3.599942 7.599934 90)
			(size 0.3556 0.3556)
			(layers "F.Cu" "F.Mask" "F.Paste")
			(net "BMC_M_A7")
		)
		(pad "AA17" smd circle
			(at 4.400042 7.599934 90)
			(size 0.3556 0.3556)
			(layers "F.Cu" "F.Mask" "F.Paste")
			(net "PVCCIO_CPU0_R")
		)
		(pad "AA18" smd circle
			(at 5.199888 7.599934 90)
			(size 0.3556 0.3556)
			(layers "F.Cu" "F.Mask" "F.Paste")
			(net "SPI_BMC_BT_CLK_R")
		)
		(pad "AA19" smd circle
			(at 5.999988 7.599934 90)
			(size 0.3556 0.3556)
			(layers "F.Cu" "F.Mask" "F.Paste")
			(net "SPI_BMC_BT_CS_R_N")
		)
		(pad "AA20" smd circle
			(at 6.800088 7.599934 90)
			(size 0.4064 0.4064)
			(layers "F.Cu" "F.Mask" "F.Paste")
			(net "GPIOS7")
		)
		(pad "AA21" smd circle
			(at 7.599934 7.599934 90)
			(size 0.4064 0.4064)
			(layers "F.Cu" "F.Mask" "F.Paste")
			(net "IRQ_BMC_PCH_SCI_LPC_N")
		)
		(pad "AA22" smd circle
			(at 8.400034 7.599934 90)
			(size 0.4064 0.4064)
			(layers "F.Cu" "F.Mask" "F.Paste")
			(net "FM_TPM_PRES_N")
		)
		(pad "AB1" smd circle
			(at -8.400034 8.400034 90)
			(size 0.4064 0.4064)
			(layers "F.Cu" "F.Mask" "F.Paste")
			(net "GND")
		)
		(pad "AB2" smd circle
			(at -7.599934 8.400034 90)
			(size 0.4064 0.4064)
			(layers "F.Cu" "F.Mask" "F.Paste")
			(net "FM_CPU1_RC_ERROR_N")
		)
		(pad "AB3" smd circle
			(at -6.800088 8.400034 90)
			(size 0.4064 0.4064)
			(layers "F.Cu" "F.Mask" "F.Paste")
			(net "PUMP_TACH0")
		)
		(pad "AB4" smd circle
			(at -5.999988 8.400034 90)
			(size 0.3556 0.3556)
			(layers "F.Cu" "F.Mask" "F.Paste")
			(net "FAN_TACH3")
		)
		(pad "AB5" smd circle
			(at -5.199888 8.400034 90)
			(size 0.3556 0.3556)
			(layers "F.Cu" "F.Mask" "F.Paste")
			(net "FM_BOARD_SKU_ID3")
		)
		(pad "AB6" smd circle
			(at -4.400042 8.400034 90)
			(size 0.3556 0.3556)
			(layers "F.Cu" "F.Mask" "F.Paste")
			(net "BMC_M_DQS1_DN")
		)
		(pad "AB7" smd circle
			(at -3.599942 8.400034 90)
			(size 0.3556 0.3556)
			(layers "F.Cu" "F.Mask" "F.Paste")
			(net "BMC_M_DQS1_DP")
		)
		(pad "AB8" smd circle
			(at -2.800096 8.400034 90)
			(size 0.3556 0.3556)
			(layers "F.Cu" "F.Mask" "F.Paste")
			(net "BMC_M_DM1")
		)
		(pad "AB9" smd circle
			(at -1.999996 8.400034 90)
			(size 0.3556 0.3556)
			(layers "F.Cu" "F.Mask" "F.Paste")
			(net "BMC_M_DQS0_DP")
		)
		(pad "AB10" smd circle
			(at -1.199896 8.400034 90)
			(size 0.3556 0.3556)
			(layers "F.Cu" "F.Mask" "F.Paste")
			(net "BMC_M_DQS0_DN")
		)
		(pad "AB11" smd circle
			(at -0.40005 8.400034 90)
			(size 0.3556 0.3556)
			(layers "F.Cu" "F.Mask" "F.Paste")
			(net "BMC_M_CLK_DP")
		)
		(pad "AB12" smd circle
			(at 0.40005 8.400034 90)
			(size 0.3556 0.3556)
			(layers "F.Cu" "F.Mask" "F.Paste")
			(net "BMC_M_CLK_DN")
		)
		(pad "AB13" smd circle
			(at 1.199896 8.400034 90)
			(size 0.3556 0.3556)
			(layers "F.Cu" "F.Mask" "F.Paste")
			(net "BMC_M_CAS_N")
		)
		(pad "AB14" smd circle
			(at 1.999996 8.400034 90)
			(size 0.3556 0.3556)
			(layers "F.Cu" "F.Mask" "F.Paste")
			(net "BMC_M_A1")
		)
		(pad "AB15" smd circle
			(at 2.800096 8.400034 90)
			(size 0.3556 0.3556)
			(layers "F.Cu" "F.Mask" "F.Paste")
			(net "BMC_M_A13")
		)
		(pad "AB16" smd circle
			(at 3.599942 8.400034 90)
			(size 0.3556 0.3556)
			(layers "F.Cu" "F.Mask" "F.Paste")
			(net "BMC_M_A6")
		)
		(pad "AB17" smd circle
			(at 4.400042 8.400034 90)
			(size 0.3556 0.3556)
			(layers "F.Cu" "F.Mask" "F.Paste")
			(net "BMC_M_RST_N")
		)
		(pad "AB18" smd circle
			(at 5.199888 8.400034 90)
			(size 0.3556 0.3556)
			(layers "F.Cu" "F.Mask" "F.Paste")
			(net "PECI_BMC_R")
		)
		(pad "AB19" smd circle
			(at 5.999988 8.400034 90)
			(size 0.3556 0.3556)
			(layers "F.Cu" "F.Mask" "F.Paste")
			(net "SPI_BMC_BT_CS0_N")
		)
		(pad "AB20" smd circle
			(at 6.800088 8.400034 90)
			(size 0.4064 0.4064)
			(layers "F.Cu" "F.Mask" "F.Paste")
			(net "FM_BMC_NMI_N_R")
		)
		(pad "AB21" smd circle
			(at 7.599934 8.400034 90)
			(size 0.4064 0.4064)
			(layers "F.Cu" "F.Mask" "F.Paste")
			(net "IRQ_PVDDQ_DEF_VRHOT_LVT3_N")
		)
		(pad "AB22" smd circle
			(at 8.400034 8.400034 90)
			(size 0.4064 0.4064)
			(layers "F.Cu" "F.Mask" "F.Paste")
			(net "GND")
		)
		(pad "B1" smd circle
			(at -8.400034 -7.599934 90)
			(size 0.4064 0.4064)
			(layers "F.Cu" "F.Mask" "F.Paste")
			(net "RMII_BMC_SPRNGVLLE_TXEN_R")
		)
		(pad "B2" smd circle
			(at -7.599934 -7.599934 90)
			(size 0.4064 0.4064)
			(layers "F.Cu" "F.Mask" "F.Paste")
			(net "Net_6480")
		)
		(pad "B3" smd circle
			(at -6.800088 -7.599934 90)
			(size 0.4064 0.4064)
			(layers "F.Cu" "F.Mask" "F.Paste")
			(net "RMII_BMC_PCH_SPRNGVLLE_TXD1_R")
		)
		(pad "B4" smd circle
			(at -5.999988 -7.599934 90)
			(size 0.3556 0.3556)
			(layers "F.Cu" "F.Mask" "F.Paste")
			(net "CLK_50M_CKMNG_BMC_1")
		)
		(pad "B5" smd circle
			(at -5.199888 -7.599934 90)
			(size 0.3556 0.3556)
			(layers "F.Cu" "F.Mask" "F.Paste")
			(net "Net_543")
		)
		(pad "B6" smd circle
			(at -4.400042 -7.599934 90)
			(size 0.3556 0.3556)
			(layers "F.Cu" "F.Mask" "F.Paste")
			(net "USB2_PCH_BMC_P5_DP")
		)
		(pad "B7" smd circle
			(at -3.599942 -7.599934 90)
			(size 0.3556 0.3556)
			(layers "F.Cu" "F.Mask" "F.Paste")
			(net "A_USB2BVRES")
		)
		(pad "B8" smd circle
			(at -2.800096 -7.599934 90)
			(size 0.3556 0.3556)
			(layers "F.Cu" "F.Mask" "F.Paste")
			(net "A_USB2AVRES")
		)
		(pad "B9" smd circle
			(at -1.999996 -7.599934 90)
			(size 0.3556 0.3556)
			(layers "F.Cu" "F.Mask" "F.Paste")
			(net "SMB_HOST_STBY_LVC3_SDA_R")
		)
		(pad "B10" smd circle
			(at -1.199896 -7.599934 90)
			(size 0.3556 0.3556)
			(layers "F.Cu" "F.Mask" "F.Paste")
			(net "FM_POST_CARD_PRES_BMC_N")
		)
		(pad "B11" smd circle
			(at -0.40005 -7.599934 90)
			(size 0.3556 0.3556)
			(layers "F.Cu" "F.Mask" "F.Paste")
			(net "SMB_PEHPCPU0_STBY_LVC3_R2_SDA")
		)
		(pad "B12" smd circle
			(at 0.40005 -7.599934 90)
			(size 0.3556 0.3556)
			(layers "F.Cu" "F.Mask" "F.Paste")
			(net "SMB_PEHPCPU0_STBY_LVC3_SCL")
		)
		(pad "B13" smd circle
			(at 1.199896 -7.599934 90)
			(size 0.3556 0.3556)
			(layers "F.Cu" "F.Mask" "F.Paste")
			(net "FM_BMC_CPLD_MP_RST_N")
		)
		(pad "B14" smd circle
			(at 1.999996 -7.599934 90)
			(size 0.3556 0.3556)
			(layers "F.Cu" "F.Mask" "F.Paste")
			(net "JTAG_RISER_N")
		)
		(pad "B15" smd circle
			(at 2.800096 -7.599934 90)
			(size 0.3556 0.3556)
			(layers "F.Cu" "F.Mask" "F.Paste")
			(net "SPI_BMC_CS0_N")
		)
		(pad "B16" smd circle
			(at 3.599942 -7.599934 90)
			(size 0.3556 0.3556)
			(layers "F.Cu" "F.Mask" "F.Paste")
			(net "FM_FORCE_ADR_N")
		)
		(pad "B17" smd circle
			(at 4.400042 -7.599934 90)
			(size 0.3556 0.3556)
			(layers "F.Cu" "F.Mask" "F.Paste")
			(net "LED_POSTCODE_5")
		)
		(pad "B18" smd circle
			(at 5.199888 -7.599934 90)
			(size 0.3556 0.3556)
			(layers "F.Cu" "F.Mask" "F.Paste")
			(net "LED_POSTCODE_1")
		)
		(pad "B19" smd circle
			(at 5.999988 -7.599934 90)
			(size 0.3556 0.3556)
			(layers "F.Cu" "F.Mask" "F.Paste")
			(net "FM_CPU1_PROCHOT_LVT3_BMC_N")
		)
		(pad "B20" smd circle
			(at 6.800088 -7.599934 90)
			(size 0.4064 0.4064)
			(layers "F.Cu" "F.Mask" "F.Paste")
			(net "RST_SYSTEM_BTN_R_N")
		)
		(pad "B21" smd circle
			(at 7.599934 -7.599934 90)
			(size 0.4064 0.4064)
			(layers "F.Cu" "F.Mask" "F.Paste")
			(net "IRQ_PVCCIN_CPU1_VRHOT_LVC3_N")
		)
		(pad "B22" smd circle
			(at 8.400034 -7.599934 90)
			(size 0.4064 0.4064)
			(layers "F.Cu" "F.Mask" "F.Paste")
			(net "IRQ_PVCCIN_CPU0_VRHOT_LVC3_N")
		)
		(pad "C1" smd circle
			(at -8.400034 -6.800088 90)
			(size 0.4064 0.4064)
			(layers "F.Cu" "F.Mask" "F.Paste")
			(net "FM_FAST_PROCHOT_EN_N")
		)
		(pad "C2" smd circle
			(at -7.599934 -6.800088 90)
			(size 0.4064 0.4064)
			(layers "F.Cu" "F.Mask" "F.Paste")
			(net "CLK_50M_CKMNG_BMC_2")
		)
		(pad "C3" smd circle
			(at -6.800088 -6.800088 90)
			(size 0.4064 0.4064)
			(layers "F.Cu" "F.Mask" "F.Paste")
			(net "RMII_SPRNGVLLE_BMC_PCH_RXD0")
		)
		(pad "C4" smd circle
			(at -5.999988 -6.800088 90)
			(size 0.3556 0.3556)
			(layers "F.Cu" "F.Mask" "F.Paste")
			(net "RMII_BMC_OCP_RXER")
		)
		(pad "C5" smd circle
			(at -5.199888 -6.800088 90)
			(size 0.3556 0.3556)
			(layers "F.Cu" "F.Mask" "F.Paste")
			(net "RMII_BMC_OCP_CRSDV")
		)
		(pad "C6" smd circle
			(at -4.400042 -6.800088 90)
			(size 0.3556 0.3556)
			(layers "F.Cu" "F.Mask" "F.Paste")
			(net "GND")
		)
		(pad "C7" smd circle
			(at -3.599942 -6.800088 90)
			(size 0.3556 0.3556)
			(layers "F.Cu" "F.Mask" "F.Paste")
			(net "P3V3_USB2A_ALG")
		)
		(pad "C8" smd circle
			(at -2.800096 -6.800088 90)
			(size 0.3556 0.3556)
			(layers "F.Cu" "F.Mask" "F.Paste")
			(net "JTAG_BMC_TMS")
		)
		(pad "C9" smd circle
			(at -1.999996 -6.800088 90)
			(size 0.3556 0.3556)
			(layers "F.Cu" "F.Mask" "F.Paste")
			(net "PU_JTAG_BMC_RTCK")
		)
		(pad "C10" smd circle
			(at -1.199896 -6.800088 90)
			(size 0.3556 0.3556)
			(layers "F.Cu" "F.Mask" "F.Paste")
			(net "JTAG_BMC_TCK")
		)
		(pad "C11" smd circle
			(at -0.40005 -6.800088 90)
			(size 0.3556 0.3556)
			(layers "F.Cu" "F.Mask" "F.Paste")
			(net "SMB_PEHPCPU0_STBY_LVC3_R2_SCL")
		)
		(pad "C12" smd circle
			(at 0.40005 -6.800088 90)
			(size 0.3556 0.3556)
			(layers "F.Cu" "F.Mask" "F.Paste")
			(net "SMB_DEBUG_STBY_LVC3_SCL_R")
		)
		(pad "C13" smd circle
			(at 1.199896 -6.800088 90)
			(size 0.3556 0.3556)
			(layers "F.Cu" "F.Mask" "F.Paste")
			(net "FM_BB_BMC_MP_GPIO")
		)
		(pad "C14" smd circle
			(at 1.999996 -6.800088 90)
			(size 0.3556 0.3556)
			(layers "F.Cu" "F.Mask" "F.Paste")
			(net "SMB_OCP_FRU_STBY_LVC3_SCL_R")
		)
		(pad "C15" smd circle
			(at 2.800096 -6.800088 90)
			(size 0.3556 0.3556)
			(layers "F.Cu" "F.Mask" "F.Paste")
			(net "SPI_BMC_CLK")
		)
		(pad "C16" smd circle
			(at 3.599942 -6.800088 90)
			(size 0.3556 0.3556)
			(layers "F.Cu" "F.Mask" "F.Paste")
			(net "FM_UV_ADR_TRIGGER_EN")
		)
		(pad "C17" smd circle
			(at 4.400042 -6.800088 90)
			(size 0.3556 0.3556)
			(layers "F.Cu" "F.Mask" "F.Paste")
			(net "LED_POSTCODE_3")
		)
		(pad "C18" smd circle
			(at 5.199888 -6.800088 90)
			(size 0.3556 0.3556)
			(layers "F.Cu" "F.Mask" "F.Paste")
			(net "FM_CPU0_FIVR_FAULT_LVT3_R_N")
		)
	)
)
